(kicad_pcb
	(version 20260206)
	(generator "pcbnew")
	(generator_version "10.0")
	(general
		(thickness 1.6)
		(legacy_teardrops no)
	)
	(paper "A4")
	(title_block
		(title "01162023_DA0F0TEBIF0_F0T_Expander_BD_F_brd_V02_OCP.brd")
		(comment 1 "Grand Teton / footprints 7410-7416 of 9728")
	)
	(layers
		(0 "F.Cu" signal "TOP")
		(4 "In1.Cu" signal "GND")
		(6 "In2.Cu" signal "VCC")
		(8 "In3.Cu" signal "VCC1")
		(10 "In4.Cu" signal "GND1")
		(12 "In5.Cu" signal "IN1")
		(14 "In6.Cu" signal "GND2")
		(16 "In7.Cu" signal "IN2")
		(18 "In8.Cu" signal "GND3")
		(20 "In9.Cu" signal "IN3")
		(22 "In10.Cu" signal "GND4")
		(24 "In11.Cu" signal "IN4")
		(26 "In12.Cu" signal "GND5")
		(28 "In13.Cu" signal "IN5")
		(30 "In14.Cu" signal "GND6")
		(32 "In15.Cu" signal "IN6")
		(34 "In16.Cu" signal "GND7")
		(2 "B.Cu" signal "BOTTOM")
		(9 "F.Adhes" user "F.Adhesive")
		(11 "B.Adhes" user "B.Adhesive")
		(13 "F.Paste" user "Package Geometry/Pastemask Top")
		(15 "B.Paste" user "Package Geometry/Pastemask Bottom")
		(5 "F.SilkS" user "Ref Des/Silkscreen Top")
		(7 "B.SilkS" user "Ref Des/Silkscreen Bottom")
		(1 "F.Mask" user "Board Geometry/Soldermask Top")
		(3 "B.Mask" user "Board Geometry/Soldermask Bottom")
		(17 "Dwgs.User" user "User.Drawings")
		(19 "Cmts.User" user "User.Comments")
		(21 "Eco1.User" user "User.Eco1")
		(23 "Eco2.User" user "User.Eco2")
		(25 "Edge.Cuts" user "Board Geometry/Outline")
		(27 "Margin" user)
		(31 "F.CrtYd" user "Package Geometry/Place Bound Top")
		(29 "B.CrtYd" user "Package Geometry/Place Bound Bottom")
		(35 "F.Fab" user "Ref Des/Assembly Top")
		(33 "B.Fab" user "Ref Des/Assembly Bottom")
	)
	(footprint ""
		(layer "B.Cu")
		(at 341.293704 -221.98711 90)
		(property "Reference" "C2030"
			(at 0 0 90)
			(layer "B.SilkS")
			(hide yes)
			(effects
				(font
					(size 1.27 1.27)
				)
				(justify mirror)
			)
		)
		(property "Value" ""
			(at 0 0 90)
			(layer "B.Fab")
			(effects
				(font
					(size 1.27 1.27)
				)
				(justify mirror)
			)
		)
		(duplicate_pad_numbers_are_jumpers no)
		(fp_line
			(start 0.69215 -0.2921)
			(end -0.69215 -0.2921)
			(stroke
				(width 0.1524)
				(type default)
			)
			(layer "B.SilkS")
		)
		(fp_line
			(start -0.69215 -0.2921)
			(end -0.69215 0.2921)
			(stroke
				(width 0.1524)
				(type default)
			)
			(layer "B.SilkS")
		)
		(fp_line
			(start 0.69215 0.2921)
			(end 0.69215 -0.2921)
			(stroke
				(width 0.1524)
				(type default)
			)
			(layer "B.SilkS")
		)
		(fp_line
			(start -0.69215 0.2921)
			(end 0.69215 0.2921)
			(stroke
				(width 0.1524)
				(type default)
			)
			(layer "B.SilkS")
		)
		(fp_line
			(start 0.51435 -0.2794)
			(end -0.51435 -0.2794)
			(stroke
				(width 0.1)
				(type default)
			)
			(layer "B.Fab")
		)
		(fp_line
			(start -0.51435 -0.2794)
			(end -0.51435 0.2794)
			(stroke
				(width 0.1)
				(type default)
			)
			(layer "B.Fab")
		)
		(fp_line
			(start 0.51435 0.2794)
			(end 0.51435 -0.2794)
			(stroke
				(width 0.1)
				(type default)
			)
			(layer "B.Fab")
		)
		(fp_line
			(start -0.51435 0.2794)
			(end 0.51435 0.2794)
			(stroke
				(width 0.1)
				(type default)
			)
			(layer "B.Fab")
		)
		(pad "1" smd circle
			(at 0.40005 0 270)
			(size 0 0)
			(layers "B.Cu" "B.Mask" "B.Paste")
			(net "P3V3_FPGA_VCCIO0")
		)
		(pad "2" smd circle
			(at -0.40005 0 270)
			(size 0 0)
			(layers "B.Cu" "B.Mask" "B.Paste")
			(net "GND")
		)
		(zone
			(layer "B.Cu")
			(hatch none 0.5)
			(connect_pads
				(clearance 0)
			)
			(min_thickness 0.25)
			(keepout
				(tracks not_allowed)
				(vias allowed)
				(pads allowed)
				(copperpour not_allowed)
				(footprints allowed)
			)
			(placement
				(enabled no)
				(sheetname "")
			)
			(fill
				(thermal_gap 0.5)
				(thermal_bridge_width 0.5)
				(island_removal_mode 0)
			)
			(polygon
				(pts
					(xy 341.381334 -222.17761) (xy 341.4395 -222.08617) (xy 341.4395 -221.88678) (xy 341.381334 -221.79661)
					(xy 341.206074 -221.79661) (xy 341.147654 -221.88678) (xy 341.147654 -222.08617) (xy 341.20582 -222.17761)
				)
			)
		)
	)
	(footprint ""
		(layer "B.Cu")
		(at 186.203844 -97.663)
		(property "Reference" "R157"
			(at 0 0 0)
			(layer "B.SilkS")
			(hide yes)
			(effects
				(font
					(size 1.27 1.27)
				)
				(justify mirror)
			)
		)
		(property "Value" ""
			(at 0 0 0)
			(layer "B.Fab")
			(effects
				(font
					(size 1.27 1.27)
				)
				(justify mirror)
			)
		)
		(duplicate_pad_numbers_are_jumpers no)
		(fp_line
			(start -0.7874 -0.4064)
			(end -0.7874 0.4064)
			(stroke
				(width 0.1524)
				(type default)
			)
			(layer "B.SilkS")
		)
		(fp_line
			(start -0.7874 0.4064)
			(end 0.7874 0.4064)
			(stroke
				(width 0.1524)
				(type default)
			)
			(layer "B.SilkS")
		)
		(fp_line
			(start 0.7874 -0.4064)
			(end -0.7874 -0.4064)
			(stroke
				(width 0.1524)
				(type default)
			)
			(layer "B.SilkS")
		)
		(fp_line
			(start 0.7874 0.4064)
			(end 0.7874 -0.4064)
			(stroke
				(width 0.1524)
				(type default)
			)
			(layer "B.SilkS")
		)
		(fp_line
			(start -0.67945 -0.3048)
			(end -0.67945 0.3048)
			(stroke
				(width 0.1)
				(type default)
			)
			(layer "B.Fab")
		)
		(fp_line
			(start -0.67945 0.3048)
			(end -0.120396 0.3048)
			(stroke
				(width 0.1)
				(type default)
			)
			(layer "B.Fab")
		)
		(fp_line
			(start -0.12065 -0.3048)
			(end -0.67945 -0.3048)
			(stroke
				(width 0.1)
				(type default)
			)
			(layer "B.Fab")
		)
		(fp_line
			(start -0.12065 -0.2794)
			(end -0.12065 -0.3048)
			(stroke
				(width 0.1)
				(type default)
			)
			(layer "B.Fab")
		)
		(fp_line
			(start -0.120396 0.2794)
			(end 0.12065 0.2794)
			(stroke
				(width 0.1)
				(type default)
			)
			(layer "B.Fab")
		)
		(fp_line
			(start -0.120396 0.3048)
			(end -0.120396 0.2794)
			(stroke
				(width 0.1)
				(type default)
			)
			(layer "B.Fab")
		)
		(fp_line
			(start 0.12065 -0.305054)
			(end 0.12065 -0.2794)
			(stroke
				(width 0.1)
				(type default)
			)
			(layer "B.Fab")
		)
		(fp_line
			(start 0.12065 -0.2794)
			(end -0.12065 -0.2794)
			(stroke
				(width 0.1)
				(type default)
			)
			(layer "B.Fab")
		)
		(fp_line
			(start 0.12065 0.2794)
			(end 0.12065 0.3048)
			(stroke
				(width 0.1)
				(type default)
			)
			(layer "B.Fab")
		)
		(fp_line
			(start 0.12065 0.3048)
			(end 0.67945 0.3048)
			(stroke
				(width 0.1)
				(type default)
			)
			(layer "B.Fab")
		)
		(fp_line
			(start 0.67945 -0.305054)
			(end 0.12065 -0.305054)
			(stroke
				(width 0.1)
				(type default)
			)
			(layer "B.Fab")
		)
		(fp_line
			(start 0.67945 0.3048)
			(end 0.67945 -0.305054)
			(stroke
				(width 0.1)
				(type default)
			)
			(layer "B.Fab")
		)
		(pad "1" smd circle
			(at 0.40005 0 180)
			(size 0 0)
			(layers "B.Cu" "B.Mask" "B.Paste")
			(net "PWRGD_NIC3_PWR_GOOD")
		)
		(pad "2" smd circle
			(at -0.40005 0 180)
			(size 0 0)
			(layers "B.Cu" "B.Mask" "B.Paste")
			(net "PWRGD_NIC3_PWR_GOOD_R")
		)
	)
	(footprint ""
		(layer "B.Cu")
		(at 246.798592 -310.548528 -90)
		(property "Reference" "R845"
			(at 0 0 90)
			(layer "B.SilkS")
			(hide yes)
			(effects
				(font
					(size 1.27 1.27)
				)
				(justify mirror)
			)
		)
		(property "Value" ""
			(at 0 0 90)
			(layer "B.Fab")
			(effects
				(font
					(size 1.27 1.27)
				)
				(justify mirror)
			)
		)
		(duplicate_pad_numbers_are_jumpers no)
		(fp_line
			(start -0.7874 0.4064)
			(end 0.7874 0.4064)
			(stroke
				(width 0.1524)
				(type default)
			)
			(layer "B.SilkS")
		)
		(fp_line
			(start 0.7874 0.4064)
			(end 0.7874 -0.4064)
			(stroke
				(width 0.1524)
				(type default)
			)
			(layer "B.SilkS")
		)
		(fp_line
			(start -0.7874 -0.4064)
			(end -0.7874 0.4064)
			(stroke
				(width 0.1524)
				(type default)
			)
			(layer "B.SilkS")
		)
		(fp_line
			(start 0.7874 -0.4064)
			(end -0.7874 -0.4064)
			(stroke
				(width 0.1524)
				(type default)
			)
			(layer "B.SilkS")
		)
		(fp_line
			(start -0.67945 0.3048)
			(end -0.120396 0.3048)
			(stroke
				(width 0.1)
				(type default)
			)
			(layer "B.Fab")
		)
		(fp_line
			(start -0.120396 0.3048)
			(end -0.120396 0.2794)
			(stroke
				(width 0.1)
				(type default)
			)
			(layer "B.Fab")
		)
		(fp_line
			(start 0.12065 0.3048)
			(end 0.67945 0.3048)
			(stroke
				(width 0.1)
				(type default)
			)
			(layer "B.Fab")
		)
		(fp_line
			(start 0.67945 0.3048)
			(end 0.67945 -0.305054)
			(stroke
				(width 0.1)
				(type default)
			)
			(layer "B.Fab")
		)
		(fp_line
			(start -0.120396 0.2794)
			(end 0.12065 0.2794)
			(stroke
				(width 0.1)
				(type default)
			)
			(layer "B.Fab")
		)
		(fp_line
			(start 0.12065 0.2794)
			(end 0.12065 0.3048)
			(stroke
				(width 0.1)
				(type default)
			)
			(layer "B.Fab")
		)
		(fp_line
			(start -0.12065 -0.2794)
			(end -0.12065 -0.3048)
			(stroke
				(width 0.1)
				(type default)
			)
			(layer "B.Fab")
		)
		(fp_line
			(start 0.12065 -0.2794)
			(end -0.12065 -0.2794)
			(stroke
				(width 0.1)
				(type default)
			)
			(layer "B.Fab")
		)
		(fp_line
			(start -0.67945 -0.3048)
			(end -0.67945 0.3048)
			(stroke
				(width 0.1)
				(type default)
			)
			(layer "B.Fab")
		)
		(fp_line
			(start -0.12065 -0.3048)
			(end -0.67945 -0.3048)
			(stroke
				(width 0.1)
				(type default)
			)
			(layer "B.Fab")
		)
		(fp_line
			(start 0.12065 -0.305054)
			(end 0.12065 -0.2794)
			(stroke
				(width 0.1)
				(type default)
			)
			(layer "B.Fab")
		)
		(fp_line
			(start 0.67945 -0.305054)
			(end 0.12065 -0.305054)
			(stroke
				(width 0.1)
				(type default)
			)
			(layer "B.Fab")
		)
		(pad "1" smd circle
			(at 0.40005 0 90)
			(size 0 0)
			(layers "B.Cu" "B.Mask" "B.Paste")
			(net "P1V25_PEX2_VCC")
		)
		(pad "2" smd circle
			(at -0.40005 0 90)
			(size 0 0)
			(layers "B.Cu" "B.Mask" "B.Paste")
			(net "PWRGD_P1V25_PEX2")
		)
	)
	(footprint ""
		(layer "B.Cu")
		(at 193.641726 -98.021648 180)
		(property "Reference" "R166"
			(at 0 0 0)
			(layer "B.SilkS")
			(hide yes)
			(effects
				(font
					(size 1.27 1.27)
				)
				(justify mirror)
			)
		)
		(property "Value" ""
			(at 0 0 0)
			(layer "B.Fab")
			(effects
				(font
					(size 1.27 1.27)
				)
				(justify mirror)
			)
		)
		(duplicate_pad_numbers_are_jumpers no)
		(fp_line
			(start 0.7874 0.4064)
			(end 0.7874 -0.4064)
			(stroke
				(width 0.1524)
				(type default)
			)
			(layer "B.SilkS")
		)
		(fp_line
			(start 0.7874 -0.4064)
			(end -0.7874 -0.4064)
			(stroke
				(width 0.1524)
				(type default)
			)
			(layer "B.SilkS")
		)
		(fp_line
			(start -0.7874 0.4064)
			(end 0.7874 0.4064)
			(stroke
				(width 0.1524)
				(type default)
			)
			(layer "B.SilkS")
		)
		(fp_line
			(start -0.7874 -0.4064)
			(end -0.7874 0.4064)
			(stroke
				(width 0.1524)
				(type default)
			)
			(layer "B.SilkS")
		)
		(fp_line
			(start 0.67945 0.3048)
			(end 0.67945 -0.305054)
			(stroke
				(width 0.1)
				(type default)
			)
			(layer "B.Fab")
		)
		(fp_line
			(start 0.67945 -0.305054)
			(end 0.12065 -0.305054)
			(stroke
				(width 0.1)
				(type default)
			)
			(layer "B.Fab")
		)
		(fp_line
			(start 0.12065 0.3048)
			(end 0.67945 0.3048)
			(stroke
				(width 0.1)
				(type default)
			)
			(layer "B.Fab")
		)
		(fp_line
			(start 0.12065 0.2794)
			(end 0.12065 0.3048)
			(stroke
				(width 0.1)
				(type default)
			)
			(layer "B.Fab")
		)
		(fp_line
			(start 0.12065 -0.2794)
			(end -0.12065 -0.2794)
			(stroke
				(width 0.1)
				(type default)
			)
			(layer "B.Fab")
		)
		(fp_line
			(start 0.12065 -0.305054)
			(end 0.12065 -0.2794)
			(stroke
				(width 0.1)
				(type default)
			)
			(layer "B.Fab")
		)
		(fp_line
			(start -0.120396 0.3048)
			(end -0.120396 0.2794)
			(stroke
				(width 0.1)
				(type default)
			)
			(layer "B.Fab")
		)
		(fp_line
			(start -0.120396 0.2794)
			(end 0.12065 0.2794)
			(stroke
				(width 0.1)
				(type default)
			)
			(layer "B.Fab")
		)
		(fp_line
			(start -0.12065 -0.2794)
			(end -0.12065 -0.3048)
			(stroke
				(width 0.1)
				(type default)
			)
			(layer "B.Fab")
		)
		(fp_line
			(start -0.12065 -0.3048)
			(end -0.67945 -0.3048)
			(stroke
				(width 0.1)
				(type default)
			)
			(layer "B.Fab")
		)
		(fp_line
			(start -0.67945 0.3048)
			(end -0.120396 0.3048)
			(stroke
				(width 0.1)
				(type default)
			)
			(layer "B.Fab")
		)
		(fp_line
			(start -0.67945 -0.3048)
			(end -0.67945 0.3048)
			(stroke
				(width 0.1)
				(type default)
			)
			(layer "B.Fab")
		)
		(pad "1" smd circle
			(at 0.40005 0)
			(size 0 0)
			(layers "B.Cu" "B.Mask" "B.Paste")
			(net "NIC3_DATA_OUT")
		)
		(pad "2" smd circle
			(at -0.40005 0)
			(size 0 0)
			(layers "B.Cu" "B.Mask" "B.Paste")
			(net "GND")
		)
	)
	(footprint ""
		(layer "B.Cu")
		(at 303.49063 -118.711218 180)
		(property "Reference" "R279"
			(at 0 0 0)
			(layer "B.SilkS")
			(hide yes)
			(effects
				(font
					(size 1.27 1.27)
				)
				(justify mirror)
			)
		)
		(property "Value" ""
			(at 0 0 0)
			(layer "B.Fab")
			(effects
				(font
					(size 1.27 1.27)
				)
				(justify mirror)
			)
		)
		(duplicate_pad_numbers_are_jumpers no)
		(fp_line
			(start 0.7874 0.4064)
			(end 0.7874 -0.4064)
			(stroke
				(width 0.1524)
				(type default)
			)
			(layer "B.SilkS")
		)
		(fp_line
			(start 0.7874 -0.4064)
			(end -0.7874 -0.4064)
			(stroke
				(width 0.1524)
				(type default)
			)
			(layer "B.SilkS")
		)
		(fp_line
			(start -0.7874 0.4064)
			(end 0.7874 0.4064)
			(stroke
				(width 0.1524)
				(type default)
			)
			(layer "B.SilkS")
		)
		(fp_line
			(start -0.7874 -0.4064)
			(end -0.7874 0.4064)
			(stroke
				(width 0.1524)
				(type default)
			)
			(layer "B.SilkS")
		)
		(fp_line
			(start 0.67945 0.3048)
			(end 0.67945 -0.305054)
			(stroke
				(width 0.1)
				(type default)
			)
			(layer "B.Fab")
		)
		(fp_line
			(start 0.67945 -0.305054)
			(end 0.12065 -0.305054)
			(stroke
				(width 0.1)
				(type default)
			)
			(layer "B.Fab")
		)
		(fp_line
			(start 0.12065 0.3048)
			(end 0.67945 0.3048)
			(stroke
				(width 0.1)
				(type default)
			)
			(layer "B.Fab")
		)
		(fp_line
			(start 0.12065 0.2794)
			(end 0.12065 0.3048)
			(stroke
				(width 0.1)
				(type default)
			)
			(layer "B.Fab")
		)
		(fp_line
			(start 0.12065 -0.2794)
			(end -0.12065 -0.2794)
			(stroke
				(width 0.1)
				(type default)
			)
			(layer "B.Fab")
		)
		(fp_line
			(start 0.12065 -0.305054)
			(end 0.12065 -0.2794)
			(stroke
				(width 0.1)
				(type default)
			)
			(layer "B.Fab")
		)
		(fp_line
			(start -0.120396 0.3048)
			(end -0.120396 0.2794)
			(stroke
				(width 0.1)
				(type default)
			)
			(layer "B.Fab")
		)
		(fp_line
			(start -0.120396 0.2794)
			(end 0.12065 0.2794)
			(stroke
				(width 0.1)
				(type default)
			)
			(layer "B.Fab")
		)
		(fp_line
			(start -0.12065 -0.2794)
			(end -0.12065 -0.3048)
			(stroke
				(width 0.1)
				(type default)
			)
			(layer "B.Fab")
		)
		(fp_line
			(start -0.12065 -0.3048)
			(end -0.67945 -0.3048)
			(stroke
				(width 0.1)
				(type default)
			)
			(layer "B.Fab")
		)
		(fp_line
			(start -0.67945 0.3048)
			(end -0.120396 0.3048)
			(stroke
				(width 0.1)
				(type default)
			)
			(layer "B.Fab")
		)
		(fp_line
			(start -0.67945 -0.3048)
			(end -0.67945 0.3048)
			(stroke
				(width 0.1)
				(type default)
			)
			(layer "B.Fab")
		)
		(pad "1" smd circle
			(at 0.40005 0)
			(size 0 0)
			(layers "B.Cu" "B.Mask" "B.Paste")
			(net "NIC5_AUX_PWR_EN")
		)
		(pad "2" smd circle
			(at -0.40005 0)
			(size 0 0)
			(layers "B.Cu" "B.Mask" "B.Paste")
			(net "GND")
		)
	)
	(footprint ""
		(layer "B.Cu")
		(at 175.749966 -292.099746 90)
		(property "Reference" "C1487"
			(at 0 0 90)
			(layer "B.SilkS")
			(hide yes)
			(effects
				(font
					(size 1.27 1.27)
				)
				(justify mirror)
			)
		)
		(property "Value" ""
			(at 0 0 90)
			(layer "B.Fab")
			(effects
				(font
					(size 1.27 1.27)
				)
				(justify mirror)
			)
		)
		(duplicate_pad_numbers_are_jumpers no)
		(fp_line
			(start 0.299974 -0.150114)
			(end -0.299974 -0.150114)
			(stroke
				(width 0.1)
				(type default)
			)
			(layer "B.Fab")
		)
		(fp_line
			(start -0.299974 -0.150114)
			(end -0.299974 0.150114)
			(stroke
				(width 0.1)
				(type default)
			)
			(layer "B.Fab")
		)
		(fp_line
			(start 0.299974 0.150114)
			(end 0.299974 -0.150114)
			(stroke
				(width 0.1)
				(type default)
			)
			(layer "B.Fab")
		)
		(fp_line
			(start -0.299974 0.150114)
			(end 0.299974 0.150114)
			(stroke
				(width 0.1)
				(type default)
			)
			(layer "B.Fab")
		)
		(pad "1" smd rect
			(at 0.2667 0 270)
			(size 0.3048 0.381)
			(layers "B.Cu" "B.Mask" "B.Paste")
			(net "P0V8_SERDES_VDDA_PEX1")
		)
		(pad "2" smd rect
			(at -0.2667 0 270)
			(size 0.3048 0.381)
			(layers "B.Cu" "B.Mask" "B.Paste")
			(net "GND")
		)
	)
	(footprint ""
		(layer "B.Cu")
		(at 397.85544 -157.0736 180)
		(property "Reference" "R307"
			(at 0 0 0)
			(layer "B.SilkS")
			(hide yes)
			(effects
				(font
					(size 1.27 1.27)
				)
				(justify mirror)
			)
		)
		(property "Value" ""
			(at 0 0 0)
			(layer "B.Fab")
			(effects
				(font
					(size 1.27 1.27)
				)
				(justify mirror)
			)
		)
		(duplicate_pad_numbers_are_jumpers no)
		(fp_line
			(start 0.7874 0.4064)
			(end 0.7874 -0.4064)
			(stroke
				(width 0.1524)
				(type default)
			)
			(layer "B.SilkS")
		)
		(fp_line
			(start 0.7874 -0.4064)
			(end -0.7874 -0.4064)
			(stroke
				(width 0.1524)
				(type default)
			)
			(layer "B.SilkS")
		)
		(fp_line
			(start -0.7874 0.4064)
			(end 0.7874 0.4064)
			(stroke
				(width 0.1524)
				(type default)
			)
			(layer "B.SilkS")
		)
		(fp_line
			(start -0.7874 -0.4064)
			(end -0.7874 0.4064)
			(stroke
				(width 0.1524)
				(type default)
			)
			(layer "B.SilkS")
		)
		(fp_line
			(start 0.67945 0.3048)
			(end 0.67945 -0.305054)
			(stroke
				(width 0.1)
				(type default)
			)
			(layer "B.Fab")
		)
		(fp_line
			(start 0.67945 -0.305054)
			(end 0.12065 -0.305054)
			(stroke
				(width 0.1)
				(type default)
			)
			(layer "B.Fab")
		)
		(fp_line
			(start 0.12065 0.3048)
			(end 0.67945 0.3048)
			(stroke
				(width 0.1)
				(type default)
			)
			(layer "B.Fab")
		)
		(fp_line
			(start 0.12065 0.2794)
			(end 0.12065 0.3048)
			(stroke
				(width 0.1)
				(type default)
			)
			(layer "B.Fab")
		)
		(fp_line
			(start 0.12065 -0.2794)
			(end -0.12065 -0.2794)
			(stroke
				(width 0.1)
				(type default)
			)
			(layer "B.Fab")
		)
		(fp_line
			(start 0.12065 -0.305054)
			(end 0.12065 -0.2794)
			(stroke
				(width 0.1)
				(type default)
			)
			(layer "B.Fab")
		)
		(fp_line
			(start -0.120396 0.3048)
			(end -0.120396 0.2794)
			(stroke
				(width 0.1)
				(type default)
			)
			(layer "B.Fab")
		)
		(fp_line
			(start -0.120396 0.2794)
			(end 0.12065 0.2794)
			(stroke
				(width 0.1)
				(type default)
			)
			(layer "B.Fab")
		)
		(fp_line
			(start -0.12065 -0.2794)
			(end -0.12065 -0.3048)
			(stroke
				(width 0.1)
				(type default)
			)
			(layer "B.Fab")
		)
		(fp_line
			(start -0.12065 -0.3048)
			(end -0.67945 -0.3048)
			(stroke
				(width 0.1)
				(type default)
			)
			(layer "B.Fab")
		)
		(fp_line
			(start -0.67945 0.3048)
			(end -0.120396 0.3048)
			(stroke
				(width 0.1)
				(type default)
			)
			(layer "B.Fab")
		)
		(fp_line
			(start -0.67945 -0.3048)
			(end -0.67945 0.3048)
			(stroke
				(width 0.1)
				(type default)
			)
			(layer "B.Fab")
		)
		(pad "1" smd circle
			(at 0.40005 0)
			(size 0 0)
			(layers "B.Cu" "B.Mask" "B.Paste")
			(net "NIC6_RBT_ARB_OUT")
		)
		(pad "2" smd circle
			(at -0.40005 0)
			(size 0 0)
			(layers "B.Cu" "B.Mask" "B.Paste")
			(net "NIC6_RBT_ARB_IN")
		)
	)
)
